(kicad_pcb
	(version 20260206)
	(generator "pcbnew")
	(generator_version "10.0")
	(general
		(thickness 1.6)
		(legacy_teardrops no)
	)
	(paper "A4")
	(title_block
		(title "Bryce Canyon_IOM_IOC_16318-2_OCP.brd")
		(comment 1 "Bryce Canyon / footprints 900-906 of 1605")
	)
	(layers
		(0 "F.Cu" signal "TOP")
		(4 "In1.Cu" signal "L2GND")
		(6 "In2.Cu" signal "L3")
		(8 "In3.Cu" signal "L4VCC")
		(10 "In4.Cu" signal "L5VCC")
		(12 "In5.Cu" signal "L6")
		(14 "In6.Cu" signal "L7GND")
		(2 "B.Cu" signal "BOTTOM")
		(9 "F.Adhes" user "F.Adhesive")
		(11 "B.Adhes" user "B.Adhesive")
		(13 "F.Paste" user "Package Geometry/Pastemask Top")
		(15 "B.Paste" user "Package Geometry/Pastemask Bottom")
		(5 "F.SilkS" user "Ref Des/Silkscreen Top")
		(7 "B.SilkS" user "Ref Des/Silkscreen Bottom")
		(1 "F.Mask" user "Board Geometry/Soldermask Top")
		(3 "B.Mask" user "Board Geometry/Soldermask Bottom")
		(17 "Dwgs.User" user "User.Drawings")
		(19 "Cmts.User" user "User.Comments")
		(21 "Eco1.User" user "User.Eco1")
		(23 "Eco2.User" user "User.Eco2")
		(25 "Edge.Cuts" user "Board Geometry/Outline")
		(27 "Margin" user)
		(31 "F.CrtYd" user "Package Geometry/Place Bound Top")
		(29 "B.CrtYd" user "Package Geometry/Place Bound Bottom")
		(35 "F.Fab" user "Ref Des/Assembly Top")
		(33 "B.Fab" user "Ref Des/Assembly Bottom")
	)
	(footprint ""
		(layer "F.Cu")
		(at 93.177106 -142.653766 -90)
		(property "Reference" "U34"
			(at 0 0 270)
			(layer "F.SilkS")
			(hide yes)
			(effects
				(font
					(size 1.27 1.27)
				)
			)
		)
		(property "Value" "TCA9555PWR-GP"
			(at 0 -6.9342 270)
			(unlocked yes)
			(layer "F.Fab")
			(hide yes)
			(effects
				(font
					(size 1.016 1.016)
					(thickness 0.1524)
				)
			)
		)
		(property "Device Type" "TSOIC24H48"
			(at 0 -8.5852 270)
			(unlocked yes)
			(layer "F.Fab")
			(hide yes)
			(effects
				(font
					(size 1.016 1.016)
					(thickness 0.1524)
				)
			)
		)
		(duplicate_pad_numbers_are_jumpers no)
		(fp_line
			(start -4.2291 3.937)
			(end -4.2291 -1.397)
			(stroke
				(width 0.1524)
				(type default)
			)
			(layer "F.SilkS")
		)
		(fp_line
			(start -4.22656 3.81)
			(end -4.2291 1.397)
			(stroke
				(width 0.508)
				(type default)
			)
			(layer "F.SilkS")
		)
		(fp_line
			(start 3.81 1.397)
			(end -4.2291 1.397)
			(stroke
				(width 0.1524)
				(type default)
			)
			(layer "F.SilkS")
		)
		(fp_line
			(start -3.429 0)
			(end -4.2291 0.8001)
			(stroke
				(width 0.1524)
				(type default)
			)
			(layer "F.SilkS")
		)
		(fp_line
			(start -4.2291 -0.8001)
			(end -3.429 0)
			(stroke
				(width 0.1524)
				(type default)
			)
			(layer "F.SilkS")
		)
		(fp_line
			(start -4.2291 -1.397)
			(end 3.81 -1.397)
			(stroke
				(width 0.1524)
				(type default)
			)
			(layer "F.SilkS")
		)
		(fp_line
			(start 3.81 -1.397)
			(end 3.81 1.397)
			(stroke
				(width 0.1524)
				(type default)
			)
			(layer "F.SilkS")
		)
		(fp_poly
			(pts
				(xy -3.90652 -1.8542) (xy 3.90652 -1.8542) (xy 3.90652 1.8542) (xy -3.90652 1.8542)
			)
			(stroke
				(width 0)
				(type default)
			)
			(fill yes)
			(layer "F.SilkS")
		)
		(fp_poly
			(pts
				(xy -4.2164 3.81) (xy 4.2164 3.81) (xy 4.22656 -3.81) (xy -4.2164 -3.81)
			)
			(stroke
				(width 0)
				(type default)
			)
			(fill no)
			(layer "F.CrtYd")
		)
		(fp_poly
			(pts
				(xy -4.22656 -3.81) (xy 4.22656 -3.81) (xy 4.22656 3.81) (xy -4.22656 3.81)
			)
			(stroke
				(width 0)
				(type default)
			)
			(fill no)
			(layer "F.Fab")
		)
		(pad "1" smd rect
			(at -3.57632 2.8194 270)
			(size 0.3556 1.524)
			(layers "F.Cu" "F.Mask" "F.Paste")
			(net "IO_EXP0_RESET#_FLT")
		)
		(pad "2" smd rect
			(at -2.92608 2.8194 270)
			(size 0.3556 1.524)
			(layers "F.Cu" "F.Mask" "F.Paste")
			(net "TCA9555_A1")
		)
		(pad "3" smd rect
			(at -2.27584 2.8194 270)
			(size 0.3556 1.524)
			(layers "F.Cu" "F.Mask" "F.Paste")
			(net "TCA9555_A2")
		)
		(pad "4" smd rect
			(at -1.6256 2.8194 270)
			(size 0.3556 1.524)
			(layers "F.Cu" "F.Mask" "F.Paste")
			(net "LED_POSTCODE_0")
		)
		(pad "5" smd rect
			(at -0.97536 2.8194 270)
			(size 0.3556 1.524)
			(layers "F.Cu" "F.Mask" "F.Paste")
			(net "LED_POSTCODE_1")
		)
		(pad "6" smd rect
			(at -0.32512 2.8194 270)
			(size 0.3556 1.524)
			(layers "F.Cu" "F.Mask" "F.Paste")
			(net "LED_POSTCODE_2")
		)
		(pad "7" smd rect
			(at 0.32512 2.8194 270)
			(size 0.3556 1.524)
			(layers "F.Cu" "F.Mask" "F.Paste")
			(net "LED_POSTCODE_3")
		)
		(pad "8" smd rect
			(at 0.97536 2.8194 270)
			(size 0.3556 1.524)
			(layers "F.Cu" "F.Mask" "F.Paste")
			(net "LED_POSTCODE_4")
		)
		(pad "9" smd rect
			(at 1.6256 2.8194 270)
			(size 0.3556 1.524)
			(layers "F.Cu" "F.Mask" "F.Paste")
			(net "LED_POSTCODE_5")
		)
		(pad "10" smd rect
			(at 2.27584 2.8194 270)
			(size 0.3556 1.524)
			(layers "F.Cu" "F.Mask" "F.Paste")
			(net "LED_POSTCODE_6")
		)
		(pad "11" smd rect
			(at 2.92608 2.8194 270)
			(size 0.3556 1.524)
			(layers "F.Cu" "F.Mask" "F.Paste")
			(net "LED_POSTCODE_7")
		)
		(pad "12" smd rect
			(at 3.57632 2.8194 270)
			(size 0.3556 1.524)
			(layers "F.Cu" "F.Mask" "F.Paste")
			(net "GND")
		)
		(pad "13" smd rect
			(at 3.57632 -2.8194 270)
			(size 0.3556 1.524)
			(layers "F.Cu" "F.Mask" "F.Paste")
			(net "DEBUG_RST_BTN_N")
		)
		(pad "14" smd rect
			(at 2.92608 -2.8194 270)
			(size 0.3556 1.524)
			(layers "F.Cu" "F.Mask" "F.Paste")
			(net "DEBUG_GPIO_BMC_1")
		)
		(pad "15" smd rect
			(at 2.27584 -2.8194 270)
			(size 0.3556 1.524)
			(layers "F.Cu" "F.Mask" "F.Paste")
			(net "DEBUG_GPIO_BMC_2")
		)
		(pad "16" smd rect
			(at 1.6256 -2.8194 270)
			(size 0.3556 1.524)
			(layers "F.Cu" "F.Mask" "F.Paste")
			(net "DEBUG_GPIO_BMC_3")
		)
		(pad "17" smd rect
			(at 0.97536 -2.8194 270)
			(size 0.3556 1.524)
			(layers "F.Cu" "F.Mask" "F.Paste")
			(net "DEBUG_GPIO_BMC_4")
		)
		(pad "18" smd rect
			(at 0.32512 -2.8194 270)
			(size 0.3556 1.524)
			(layers "F.Cu" "F.Mask" "F.Paste")
			(net "DEBUG_GPIO_BMC_5")
		)
		(pad "19" smd rect
			(at -0.32512 -2.8194 270)
			(size 0.3556 1.524)
			(layers "F.Cu" "F.Mask" "F.Paste")
			(net "DEBUG_GPIO_BMC_6")
		)
		(pad "20" smd rect
			(at -0.97536 -2.8194 270)
			(size 0.3556 1.524)
			(layers "F.Cu" "F.Mask" "F.Paste")
			(net "DEBUG_HDR_UART_SEL")
		)
		(pad "21" smd rect
			(at -1.6256 -2.8194 270)
			(size 0.3556 1.524)
			(layers "F.Cu" "F.Mask" "F.Paste")
			(net "TCA9555_A0")
		)
		(pad "22" smd rect
			(at -2.27584 -2.8194 270)
			(size 0.3556 1.524)
			(layers "F.Cu" "F.Mask" "F.Paste")
			(net "I2C_DEBUG_SCL_R")
		)
		(pad "23" smd rect
			(at -2.92608 -2.8194 270)
			(size 0.3556 1.524)
			(layers "F.Cu" "F.Mask" "F.Paste")
			(net "I2C_DEBUG_SDA_R")
		)
		(pad "24" smd rect
			(at -3.57632 -2.8194 270)
			(size 0.3556 1.524)
			(layers "F.Cu" "F.Mask" "F.Paste")
			(net "P3V3_STBY")
		)
	)
	(footprint ""
		(layer "F.Cu")
		(at 74.423016 -174.78248 -90)
		(property "Reference" "C190"
			(at 0 0 270)
			(layer "F.SilkS")
			(hide yes)
			(effects
				(font
					(size 1.27 1.27)
				)
			)
		)
		(property "Value" "SC1KP50V2KX-1GP"
			(at 1.1811 -2.7051 270)
			(unlocked yes)
			(layer "F.Fab")
			(hide yes)
			(effects
				(font
					(size 1.016 1.016)
					(thickness 0.1524)
				)
			)
		)
		(property "Device Type" "C402H22"
			(at 1.1811 -4.2291 270)
			(unlocked yes)
			(layer "F.Fab")
			(hide yes)
			(effects
				(font
					(size 1.016 1.016)
					(thickness 0.1524)
				)
			)
		)
		(duplicate_pad_numbers_are_jumpers no)
		(fp_rect
			(start -0.4318 0.9525)
			(end 0.4318 -0.9525)
			(stroke
				(width 0)
				(type default)
			)
			(fill no)
			(layer "F.CrtYd")
		)
		(fp_rect
			(start -0.4318 0.9525)
			(end 0.4318 -0.9525)
			(stroke
				(width 0)
				(type default)
			)
			(fill no)
			(layer "F.Fab")
		)
		(pad "1" smd custom
			(at 0 -0.4445 270)
			(size 0.1524 0.1524)
			(layers "F.Cu" "F.Mask" "F.Paste")
			(net "TPS74801_P2V5_STBY_OUT")
			(options
				(clearance outline)
				(anchor circle)
			)
			(primitives
				(gr_poly
					(pts
						(arc
							(start 0.3048 -0.2032)
							(mid 0.275042 -0.275042)
							(end 0.2032 -0.3048)
						)
						(arc
							(start -0.2032 -0.3048)
							(mid -0.275042 -0.275042)
							(end -0.3048 -0.2032)
						)
						(arc
							(start -0.3048 0.2032)
							(mid -0.275042 0.275042)
							(end -0.2032 0.3048)
						)
						(arc
							(start 0.2032 0.3048)
							(mid 0.275042 0.275042)
							(end 0.3048 0.2032)
						)
					)
					(width 0)
					(fill yes)
				)
			)
		)
		(pad "2" smd custom
			(at 0 0.4445 270)
			(size 0.1524 0.1524)
			(layers "F.Cu" "F.Mask" "F.Paste")
			(net "TPS74801_P2V5_STBY_FB")
			(options
				(clearance outline)
				(anchor circle)
			)
			(primitives
				(gr_poly
					(pts
						(arc
							(start 0.3048 -0.2032)
							(mid 0.275042 -0.275042)
							(end 0.2032 -0.3048)
						)
						(arc
							(start -0.2032 -0.3048)
							(mid -0.275042 -0.275042)
							(end -0.3048 -0.2032)
						)
						(arc
							(start -0.3048 0.2032)
							(mid -0.275042 0.275042)
							(end -0.2032 0.3048)
						)
						(arc
							(start 0.2032 0.3048)
							(mid 0.275042 0.275042)
							(end 0.3048 0.2032)
						)
					)
					(width 0)
					(fill yes)
				)
			)
		)
	)
	(footprint ""
		(layer "F.Cu")
		(at 98.27895 -176.116234 -90)
		(property "Reference" "R736"
			(at 0 0 270)
			(layer "F.SilkS")
			(hide yes)
			(effects
				(font
					(size 1.27 1.27)
				)
			)
		)
		(property "Value" "0R2J-2-GP"
			(at 0.064008 -3.993896 270)
			(unlocked yes)
			(layer "F.Fab")
			(hide yes)
			(effects
				(font
					(size 1.016 1.016)
					(thickness 0.1524)
				)
			)
		)
		(property "Device Type" "R402H16"
			(at 0.064008 -5.517896 270)
			(unlocked yes)
			(layer "F.Fab")
			(hide yes)
			(effects
				(font
					(size 1.016 1.016)
					(thickness 0.1524)
				)
			)
		)
		(duplicate_pad_numbers_are_jumpers no)
		(fp_line
			(start -0.508 -0.9398)
			(end -0.508 0.9398)
			(stroke
				(width 0.1524)
				(type default)
			)
			(layer "F.SilkS")
		)
		(fp_line
			(start 0.508 -0.9398)
			(end -0.508 -0.9398)
			(stroke
				(width 0.1524)
				(type default)
			)
			(layer "F.SilkS")
		)
		(fp_rect
			(start -0.508 0.9398)
			(end 0.508 -0.9398)
			(stroke
				(width 0)
				(type default)
			)
			(fill no)
			(layer "F.CrtYd")
		)
		(fp_rect
			(start -0.508 0.9398)
			(end 0.508 -0.9398)
			(stroke
				(width 0)
				(type default)
			)
			(fill no)
			(layer "F.Fab")
		)
		(pad "1" smd custom
			(at 0 -0.4445 270)
			(size 0.1397 0.1397)
			(layers "F.Cu" "F.Mask" "F.Paste")
			(net "PWRGD_P3V3_STBY_N")
			(options
				(clearance outline)
				(anchor circle)
			)
			(primitives
				(gr_poly
					(pts
						(arc
							(start -0.1778 -0.2794)
							(mid -0.249642 -0.249642)
							(end -0.2794 -0.1778)
						)
						(arc
							(start -0.2794 0.1778)
							(mid -0.249642 0.249642)
							(end -0.1778 0.2794)
						)
						(arc
							(start 0.1778 0.2794)
							(mid 0.249642 0.249642)
							(end 0.2794 0.1778)
						)
						(arc
							(start 0.2794 -0.1778)
							(mid 0.249642 -0.249642)
							(end 0.1778 -0.2794)
						)
					)
					(width 0)
					(fill yes)
				)
			)
		)
		(pad "2" smd custom
			(at 0 0.4445 270)
			(size 0.1397 0.1397)
			(layers "F.Cu" "F.Mask" "F.Paste")
			(net "PWRGD_P3V3_STBY_N_R2")
			(options
				(clearance outline)
				(anchor circle)
			)
			(primitives
				(gr_poly
					(pts
						(arc
							(start -0.1778 -0.2794)
							(mid -0.249642 -0.249642)
							(end -0.2794 -0.1778)
						)
						(arc
							(start -0.2794 0.1778)
							(mid -0.249642 0.249642)
							(end -0.1778 0.2794)
						)
						(arc
							(start 0.1778 0.2794)
							(mid 0.249642 0.249642)
							(end 0.2794 0.1778)
						)
						(arc
							(start 0.2794 -0.1778)
							(mid 0.249642 -0.249642)
							(end 0.1778 -0.2794)
						)
					)
					(width 0)
					(fill yes)
				)
			)
		)
	)
	(footprint ""
		(layer "F.Cu")
		(at 204.1144 -85.1916 135)
		(property "Reference" "VIA17"
			(at 0 0 135)
			(layer "F.SilkS")
			(hide yes)
			(effects
				(font
					(size 1.27 1.27)
				)
			)
		)
		(property "Value" "85OHM-8L-1D6MM-L16L18-GP"
			(at 4.064105 0.609655 135)
			(unlocked yes)
			(layer "F.Fab")
			(hide yes)
			(effects
				(font
					(size 1.016 1.016)
					(thickness 0.1524)
				)
			)
		)
		(property "Device Type" "VIA-PCIE-4P-368076"
			(at 4.064105 -0.914474 135)
			(unlocked yes)
			(layer "F.Fab")
			(hide yes)
			(effects
				(font
					(size 1.016 1.016)
					(thickness 0.1524)
				)
			)
		)
		(duplicate_pad_numbers_are_jumpers no)
		(fp_poly
			(pts
				(xy -1.841491 -0.381057) (xy 1.841509 -0.381058) (xy 1.841508 0.380942) (xy -1.841491 0.380942)
			)
			(stroke
				(width 0)
				(type default)
			)
			(fill no)
			(layer "F.CrtYd")
		)
		(fp_poly
			(pts
				(xy -1.841491 -0.381057) (xy 1.841509 -0.381058) (xy 1.841508 0.380942) (xy -1.841491 0.380942)
			)
			(stroke
				(width 0)
				(type default)
			)
			(fill no)
			(layer "F.Fab")
		)
		(pad "1" thru_hole circle
			(at -1.460499 0 135)
			(size 0.508 0.508)
			(drill 0.254)
			(layers "*.Cu" "*.Mask")
			(remove_unused_layers no)
			(net "GND")
			(clearance 0.127)
			(thermal_gap 0.127)
		)
		(pad "2" thru_hole circle
			(at -0.4445 0 135)
			(size 0.508 0.508)
			(drill 0.254)
			(layers "*.Cu" "*.Mask")
			(remove_unused_layers no)
			(net "PCIE_COMP_TO_IOM_8_DP")
			(clearance 0.127)
			(thermal_gap 0.127)
		)
		(pad "3" thru_hole circle
			(at 0.4445 0 135)
			(size 0.508 0.508)
			(drill 0.254)
			(layers "*.Cu" "*.Mask")
			(remove_unused_layers no)
			(net "PCIE_COMP_TO_IOM_8_DN")
			(clearance 0.127)
			(thermal_gap 0.127)
		)
		(pad "4" thru_hole circle
			(at 1.460499 0 135)
			(size 0.508 0.508)
			(drill 0.254)
			(layers "*.Cu" "*.Mask")
			(remove_unused_layers no)
			(net "GND")
			(clearance 0.127)
			(thermal_gap 0.127)
		)
	)
	(footprint ""
		(layer "F.Cu")
		(at 185.928 -86.7156)
		(property "Reference" "TP145"
			(at 0 0 0)
			(layer "F.SilkS")
			(hide yes)
			(effects
				(font
					(size 1.27 1.27)
				)
			)
		)
		(property "Value" "TPAD28-2-GP"
			(at -0.0127 -1.6637 0)
			(unlocked yes)
			(layer "F.Fab")
			(hide yes)
			(effects
				(font
					(size 1.016 1.016)
					(thickness 0.1524)
				)
			)
		)
		(property "Device Type" "TPAD28"
			(at -0.0127 -3.1877 0)
			(unlocked yes)
			(layer "F.Fab")
			(hide yes)
			(effects
				(font
					(size 1.016 1.016)
					(thickness 0.1524)
				)
			)
		)
		(duplicate_pad_numbers_are_jumpers no)
		(fp_poly
			(pts
				(arc
					(start 0.3556 0)
					(mid -0.3556 0)
					(end 0.3556 0)
				)
			)
			(stroke
				(width 0)
				(type default)
			)
			(fill no)
			(layer "F.CrtYd")
		)
		(fp_poly
			(pts
				(arc
					(start 0.6096 0)
					(mid -0.6096 0)
					(end 0.6096 0)
				)
			)
			(stroke
				(width 0)
				(type default)
			)
			(fill no)
			(layer "F.Fab")
		)
		(pad "1" smd circle
			(at 0 0)
			(size 0.7112 0.7112)
			(layers "F.Cu" "F.Mask" "F.Paste")
			(net "SYS_ERROR1")
		)
	)
	(footprint ""
		(layer "F.Cu")
		(at 152.4762 -145.8976)
		(property "Reference" "CN5"
			(at 0 0 0)
			(layer "F.SilkS")
			(hide yes)
			(effects
				(font
					(size 1.27 1.27)
				)
			)
		)
		(property "Value" "PIN-CON3-5-GP"
			(at -5.334 -8.128 0)
			(unlocked yes)
			(layer "F.Fab")
			(hide yes)
			(effects
				(font
					(size 1.016 1.016)
					(thickness 0.1524)
				)
			)
		)
		(property "Device Type" "211-91-03GB01"
			(at -5.334 -9.652 0)
			(unlocked yes)
			(layer "F.Fab")
			(hide yes)
			(effects
				(font
					(size 1.016 1.016)
					(thickness 0.1524)
				)
			)
		)
		(duplicate_pad_numbers_are_jumpers no)
		(fp_line
			(start -3.8862 -10.16)
			(end -3.8862 0.9652)
			(stroke
				(width 0.1524)
				(type default)
			)
			(layer "F.SilkS")
		)
		(fp_line
			(start -3.8862 0.9652)
			(end 3.8862 0.9652)
			(stroke
				(width 0.1524)
				(type default)
			)
			(layer "F.SilkS")
		)
		(fp_line
			(start 2.742438 1.09601)
			(end 4.012438 1.09601)
			(stroke
				(width 0.4064)
				(type default)
			)
			(layer "F.SilkS")
		)
		(fp_line
			(start 3.8862 -10.16)
			(end -3.8862 -10.16)
			(stroke
				(width 0.1524)
				(type default)
			)
			(layer "F.SilkS")
		)
		(fp_line
			(start 3.8862 0.9652)
			(end 3.8862 -10.16)
			(stroke
				(width 0.1524)
				(type default)
			)
			(layer "F.SilkS")
		)
		(fp_line
			(start 4.012438 1.09601)
			(end 4.012438 -0.17399)
			(stroke
				(width 0.4064)
				(type default)
			)
			(layer "F.SilkS")
		)
		(fp_circle
			(center -2.54 0)
			(end -1.4732 0)
			(stroke
				(width 0.3048)
				(type default)
			)
			(fill no)
			(layer "F.SilkS")
		)
		(fp_circle
			(center 0 0)
			(end 1.0668 0)
			(stroke
				(width 0.3048)
				(type default)
			)
			(fill no)
			(layer "F.SilkS")
		)
		(fp_circle
			(center 2.54 0)
			(end 3.6068 0)
			(stroke
				(width 0.3048)
				(type default)
			)
			(fill no)
			(layer "F.SilkS")
		)
		(fp_rect
			(start -3.6322 0.3302)
			(end 3.6322 -9.906)
			(stroke
				(width 0)
				(type default)
			)
			(fill no)
			(layer "F.CrtYd")
		)
		(fp_poly
			(pts
				(xy 4.1402 -9.906) (xy -3.6322 -9.906) (xy -3.6322 0.3302) (xy 3.6322 0.3302) (xy 3.6322 -9.8933)
				(xy 4.1402 -9.8933) (xy 4.1402 1.2192) (xy -4.1402 1.2192) (xy -4.1402 -10.414) (xy 4.1402 -10.414)
			)
			(stroke
				(width 0)
				(type default)
			)
			(fill no)
			(layer "F.CrtYd")
		)
		(fp_rect
			(start -4.1402 1.2192)
			(end 4.1402 -10.414)
			(stroke
				(width 0)
				(type default)
			)
			(fill no)
			(layer "F.Fab")
		)
		(pad "1" thru_hole circle
			(at 2.54 0)
			(size 1.4224 1.4224)
			(drill 1.016)
			(layers "*.Cu" "*.Mask")
			(remove_unused_layers no)
			(net "IOM_IOC_UART_TX")
			(clearance 0.1524)
			(thermal_gap 0.1524)
		)
		(pad "2" thru_hole circle
			(at 0 0)
			(size 1.4224 1.4224)
			(drill 1.016)
			(layers "*.Cu" "*.Mask")
			(remove_unused_layers no)
			(net "IOM_IOC_UART_RX")
			(clearance 0.1524)
			(thermal_gap 0.1524)
		)
		(pad "3" thru_hole circle
			(at -2.54 0)
			(size 1.4224 1.4224)
			(drill 1.016)
			(layers "*.Cu" "*.Mask")
			(remove_unused_layers no)
			(net "GND")
			(clearance 0.1524)
			(thermal_gap 0.1524)
		)
	)
	(footprint ""
		(layer "F.Cu")
		(at 79.99984 -119.99976)
		(property "Reference" ""
			(at 0 0 0)
			(layer "F.SilkS")
			(hide yes)
			(effects
				(font
					(size 1.27 1.27)
				)
			)
		)
		(property "Value" "*"
			(at -6.38175 0.19685 0)
			(unlocked yes)
			(layer "F.Fab")
			(hide yes)
			(effects
				(font
					(size 1.016 1.016)
					(thickness 0.1524)
				)
			)
		)
		(duplicate_pad_numbers_are_jumpers no)
		(fp_poly
			(pts
				(arc
					(start 5.0673 0)
					(mid -5.0673 0)
					(end 5.0673 0)
				)
			)
			(stroke
				(width 0)
				(type default)
			)
			(fill no)
			(layer "B.CrtYd")
		)
		(fp_poly
			(pts
				(arc
					(start 5.0673 0)
					(mid -5.0673 0)
					(end 5.0673 0)
				)
			)
			(stroke
				(width 0)
				(type default)
			)
			(fill no)
			(layer "F.CrtYd")
		)
		(fp_poly
			(pts
				(arc
					(start 5.0673 0)
					(mid -5.0673 0)
					(end 5.0673 0)
				)
			)
			(stroke
				(width 0)
				(type default)
			)
			(fill no)
			(layer "B.Fab")
		)
		(fp_poly
			(pts
				(arc
					(start 5.0673 0)
					(mid -5.0673 0)
					(end 5.0673 0)
				)
			)
			(stroke
				(width 0)
				(type default)
			)
			(fill no)
			(layer "F.Fab")
		)
		(pad "1" thru_hole circle
			(at 0 0)
			(size 9.525 9.525)
			(drill 3.5052)
			(layers "*.Cu" "*.Mask")
			(remove_unused_layers no)
			(net "Net_9")
			(clearance -2.5019)
			(thermal_gap 0.3048)
			(padstack
				(mode front_inner_back)
				(layer "Inner"
					(shape circle)
					(size 3.9116 3.9116)
					(clearance 0.3048)
				)
				(layer "B.Cu"
					(shape circle)
					(size 9.525 9.525)
					(clearance -2.5019)
				)
			)
		)
	)
)
